(kicad_pcb
	(version 20241229)
	(generator "pcbnew")
	(generator_version "9.0")
	(general
		(thickness 1.61)
		(legacy_teardrops no)
	)
	(paper "A3")
	(title_block
		(title "SO-DIMM DDR5 Tester")
		(date "2025-11-26")
		(rev "1.3.0")
		(comment 9 "footprints 548-553 of 627")
	)
	(layers
		(0 "F.Cu" signal)
		(4 "In1.Cu" power)
		(6 "In2.Cu" mixed)
		(8 "In3.Cu" power)
		(10 "In4.Cu" mixed)
		(12 "In5.Cu" power)
		(14 "In6.Cu" mixed)
		(16 "In7.Cu" power)
		(18 "In8.Cu" power)
		(20 "In9.Cu" mixed)
		(22 "In10.Cu" power)
		(2 "B.Cu" signal)
		(9 "F.Adhes" user "F.Adhesive")
		(11 "B.Adhes" user "B.Adhesive")
		(13 "F.Paste" user)
		(15 "B.Paste" user)
		(5 "F.SilkS" user "F.Silkscreen")
		(7 "B.SilkS" user "B.Silkscreen")
		(1 "F.Mask" user)
		(3 "B.Mask" user)
		(17 "Dwgs.User" user "User.Drawings")
		(19 "Cmts.User" user "User.Comments")
		(21 "Eco1.User" user "User.Eco1")
		(23 "Eco2.User" user "User.Eco2")
		(25 "Edge.Cuts" user)
		(27 "Margin" user)
		(31 "F.CrtYd" user "F.Courtyard")
		(29 "B.CrtYd" user "B.Courtyard")
		(35 "F.Fab" user)
		(33 "B.Fab" user)
	)
	(footprint "antmicro-footprints:R_0402_1005Metric"
		(layer "B.Cu")
		(at 114.800502 182.6 180)
		(descr "Resistor SMD 0402")
		(tags "resistor SMD 0402")
		(property "Reference" "R4"
			(at -1.122484 0.772697 0)
			(layer "B.SilkS")
			(hide yes)
			(effects
				(font
					(size 0.7 0.7)
					(thickness 0.15)
				)
				(justify left bottom mirror)
			)
		)
		(property "Value" "R_4k7_0402"
			(at -1.011843 -1.772047 0)
			(layer "B.Fab")
			(effects
				(font
					(size 0.7 0.7)
					(thickness 0.15)
				)
				(justify left bottom mirror)
			)
		)
		(property "Datasheet" "https://www.bourns.com/docs/product-datasheets/cr.pdf"
			(at 0 0 180)
			(layer "F.Fab")
			(hide yes)
			(effects
				(font
					(size 1.27 1.27)
					(thickness 0.15)
				)
			)
		)
		(property "Author" "Antmicro"
			(at 229.601004 365.2 0)
			(layer "B.Fab")
			(hide yes)
			(effects
				(font
					(size 1 1)
					(thickness 0.15)
				)
				(justify mirror)
			)
		)
		(property "License" "Apache-2.0"
			(at 229.601004 365.2 0)
			(layer "B.Fab")
			(hide yes)
			(effects
				(font
					(size 1 1)
					(thickness 0.15)
				)
				(justify mirror)
			)
		)
		(property "MPN" "CR0402-FX-4701GLF"
			(at 229.601004 365.2 0)
			(layer "B.Fab")
			(hide yes)
			(effects
				(font
					(size 1 1)
					(thickness 0.15)
				)
				(justify mirror)
			)
		)
		(property "Manufacturer" "Bourns"
			(at 229.601004 365.2 0)
			(layer "B.Fab")
			(hide yes)
			(effects
				(font
					(size 1 1)
					(thickness 0.15)
				)
				(justify mirror)
			)
		)
		(property "Tolerance" "1%"
			(at 229.601004 365.2 0)
			(layer "B.Fab")
			(hide yes)
			(effects
				(font
					(size 1 1)
					(thickness 0.15)
				)
				(justify mirror)
			)
		)
		(property "Val" "4k7"
			(at 229.601004 365.2 0)
			(layer "B.Fab")
			(hide yes)
			(effects
				(font
					(size 1 1)
					(thickness 0.15)
				)
				(justify mirror)
			)
		)
		(sheetname "/HyperRAM + QSPI Flash/")
		(sheetfile "hyperram-flash.kicad_sch")
		(attr smd)
		(fp_rect
			(start -0.93 0.47)
			(end 0.93 -0.47)
			(stroke
				(width 0.05)
				(type solid)
			)
			(fill no)
			(layer "B.CrtYd")
		)
		(fp_rect
			(start -0.5 0.25)
			(end 0.5 -0.25)
			(stroke
				(width 0.15)
				(type solid)
			)
			(fill no)
			(layer "B.Fab")
		)
		(pad "1" smd roundrect
			(at -0.485 0 180)
			(size 0.59 0.64)
			(layers "B.Cu" "B.Mask" "B.Paste")
			(roundrect_rratio 0.25)
			(net 200 "+3V3")
			(pintype "passive")
		)
		(pad "2" smd roundrect
			(at 0.485 0 180)
			(size 0.59 0.64)
			(layers "B.Cu" "B.Mask" "B.Paste")
			(roundrect_rratio 0.25)
			(net 360 "/HyperRAM + QSPI Flash/IO3")
			(pintype "passive")
		)
	)
	(footprint "antmicro-footprints:TP_SMD_1mm"
		(layer "B.Cu")
		(at 186.4 164.5845 180)
		(property "Reference" "TP31"
			(at 0 0.731898 0)
			(layer "B.SilkS")
			(hide yes)
			(effects
				(font
					(size 0.7 0.7)
					(thickness 0.15)
				)
				(justify left bottom mirror)
			)
		)
		(property "Value" "TP_1mm_SMD"
			(at 0 -1.4 0)
			(layer "B.Fab")
			(effects
				(font
					(size 0.7 0.7)
					(thickness 0.15)
				)
				(justify left bottom mirror)
			)
		)
		(property "MPN" ""
			(at 0 0 0)
			(unlocked yes)
			(layer "B.Fab")
			(hide yes)
			(effects
				(font
					(size 1 1)
					(thickness 0.15)
				)
				(justify mirror)
			)
		)
		(property "Manufacturer" ""
			(at 0 0 0)
			(unlocked yes)
			(layer "B.Fab")
			(hide yes)
			(effects
				(font
					(size 1 1)
					(thickness 0.15)
				)
				(justify mirror)
			)
		)
		(property "Author" "Antmicro"
			(at 0 0 0)
			(unlocked yes)
			(layer "B.Fab")
			(hide yes)
			(effects
				(font
					(size 1 1)
					(thickness 0.15)
				)
				(justify mirror)
			)
		)
		(property "License" "Apache-2.0"
			(at 0 0 0)
			(unlocked yes)
			(layer "B.Fab")
			(hide yes)
			(effects
				(font
					(size 1 1)
					(thickness 0.15)
				)
				(justify mirror)
			)
		)
		(sheetname "/Supply/")
		(sheetfile "supply.kicad_sch")
		(attr exclude_from_pos_files)
		(fp_circle
			(center 0 0)
			(end 0.6 0)
			(stroke
				(width 0.05)
				(type default)
			)
			(fill no)
			(layer "B.CrtYd")
		)
		(fp_text user "License: Apache-2.0"
			(at -0.5 -5.2 0)
			(layer "B.Fab")
			(effects
				(font
					(size 0.7 0.7)
					(thickness 0.15)
				)
				(justify left bottom mirror)
			)
		)
		(fp_text user "Author: Antmicro"
			(at -0.5 -4 0)
			(layer "B.Fab")
			(effects
				(font
					(size 0.7 0.7)
					(thickness 0.15)
				)
				(justify left bottom mirror)
			)
		)
		(fp_text user "${REFERENCE}"
			(at -0.5 -2.8 0)
			(layer "B.Fab")
			(effects
				(font
					(size 0.7 0.7)
					(thickness 0.15)
				)
				(justify left bottom mirror)
			)
		)
		(pad "1" smd circle
			(at 0 0 180)
			(size 1 1)
			(layers "B.Cu" "B.Mask")
			(net 201 "+5V")
			(pinfunction "1")
			(pintype "passive")
		)
	)
	(footprint "antmicro-footprints:C_0402_1005Metric"
		(layer "B.Cu")
		(at 105.96 176.204 90)
		(descr "Capacitor SMD 0402")
		(tags "capacitor SMD 0402")
		(property "Reference" "C238"
			(at 0 0.699001 90)
			(layer "B.SilkS")
			(hide yes)
			(effects
				(font
					(size 0.7 0.7)
					(thickness 0.15)
				)
				(justify right bottom mirror)
			)
		)
		(property "Value" "C_100n_0402"
			(at -1.022927 -2.155213 90)
			(layer "B.Fab")
			(effects
				(font
					(size 0.7 0.7)
					(thickness 0.15)
				)
				(justify right bottom mirror)
			)
		)
		(property "Datasheet" "https://www.murata.com/products/productdetail?partno=GRM155R61H104KE14%23"
			(at 0 0 90)
			(layer "F.Fab")
			(hide yes)
			(effects
				(font
					(size 1.27 1.27)
					(thickness 0.15)
				)
			)
		)
		(property "Author" "Antmicro"
			(at 282.164 70.244 0)
			(layer "B.Fab")
			(hide yes)
			(effects
				(font
					(size 1 1)
					(thickness 0.15)
				)
				(justify mirror)
			)
		)
		(property "Dielectric" "X5R"
			(at 282.164 70.244 0)
			(layer "B.Fab")
			(hide yes)
			(effects
				(font
					(size 1 1)
					(thickness 0.15)
				)
				(justify mirror)
			)
		)
		(property "License" "Apache-2.0"
			(at 282.164 70.244 0)
			(layer "B.Fab")
			(hide yes)
			(effects
				(font
					(size 1 1)
					(thickness 0.15)
				)
				(justify mirror)
			)
		)
		(property "MPN" "GRM155R61H104KE14D"
			(at 282.164 70.244 0)
			(layer "B.Fab")
			(hide yes)
			(effects
				(font
					(size 1 1)
					(thickness 0.15)
				)
				(justify mirror)
			)
		)
		(property "Manufacturer" "Murata"
			(at 282.164 70.244 0)
			(layer "B.Fab")
			(hide yes)
			(effects
				(font
					(size 1 1)
					(thickness 0.15)
				)
				(justify mirror)
			)
		)
		(property "Val" "100n"
			(at 282.164 70.244 0)
			(layer "B.Fab")
			(hide yes)
			(effects
				(font
					(size 1 1)
					(thickness 0.15)
				)
				(justify mirror)
			)
		)
		(property "Voltage" "50V"
			(at 282.164 70.244 0)
			(layer "B.Fab")
			(hide yes)
			(effects
				(font
					(size 1 1)
					(thickness 0.15)
				)
				(justify mirror)
			)
		)
		(sheetname "/Debug FTDI/")
		(sheetfile "debug-ftdi.kicad_sch")
		(attr smd)
		(fp_rect
			(start -0.925 0.47)
			(end 0.925 -0.47)
			(stroke
				(width 0.05)
				(type default)
			)
			(fill no)
			(layer "B.CrtYd")
		)
		(fp_line
			(start 0.504 -0.248)
			(end -0.494 -0.248)
			(stroke
				(width 0.15)
				(type solid)
			)
			(layer "B.Fab")
		)
		(fp_line
			(start -0.494 -0.248)
			(end -0.494 0.25)
			(stroke
				(width 0.15)
				(type solid)
			)
			(layer "B.Fab")
		)
		(fp_line
			(start 0.504 0.25)
			(end 0.504 -0.248)
			(stroke
				(width 0.15)
				(type solid)
			)
			(layer "B.Fab")
		)
		(fp_line
			(start -0.494 0.25)
			(end 0.504 0.25)
			(stroke
				(width 0.15)
				(type solid)
			)
			(layer "B.Fab")
		)
		(pad "1" smd roundrect
			(at -0.48 0 90)
			(size 0.59 0.64)
			(layers "B.Cu" "B.Mask" "B.Paste")
			(roundrect_rratio 0.25)
			(net 1 "GND")
			(pintype "passive")
		)
		(pad "2" smd roundrect
			(at 0.48 0 90)
			(size 0.59 0.64)
			(layers "B.Cu" "B.Mask" "B.Paste")
			(roundrect_rratio 0.25)
			(net 200 "+3V3")
			(pintype "passive")
		)
	)
	(footprint "antmicro-footprints:C_0402_1005Metric"
		(layer "B.Cu")
		(at 100.280501 143.546 90)
		(descr "Capacitor SMD 0402")
		(tags "capacitor SMD 0402")
		(property "Reference" "C165"
			(at 0 0.699 270)
			(layer "B.SilkS")
			(hide yes)
			(effects
				(font
					(size 0.7 0.7)
					(thickness 0.15)
				)
				(justify left bottom mirror)
			)
		)
		(property "Value" "C_100n_0402"
			(at -1.022927 -2.155213 270)
			(layer "B.Fab")
			(effects
				(font
					(size 0.7 0.7)
					(thickness 0.15)
				)
				(justify left bottom mirror)
			)
		)
		(property "Datasheet" "https://www.murata.com/products/productdetail?partno=GRM155R61H104KE14%23"
			(at 0 0 90)
			(layer "F.Fab")
			(hide yes)
			(effects
				(font
					(size 1.27 1.27)
					(thickness 0.15)
				)
			)
		)
		(property "Author" "Antmicro"
			(at 243.826501 43.265499 0)
			(layer "B.Fab")
			(hide yes)
			(effects
				(font
					(size 1 1)
					(thickness 0.15)
				)
				(justify mirror)
			)
		)
		(property "Dielectric" "X5R"
			(at 243.826501 43.265499 0)
			(layer "B.Fab")
			(hide yes)
			(effects
				(font
					(size 1 1)
					(thickness 0.15)
				)
				(justify mirror)
			)
		)
		(property "License" "Apache-2.0"
			(at 243.826501 43.265499 0)
			(layer "B.Fab")
			(hide yes)
			(effects
				(font
					(size 1 1)
					(thickness 0.15)
				)
				(justify mirror)
			)
		)
		(property "MPN" "GRM155R61H104KE14D"
			(at 243.826501 43.265499 0)
			(layer "B.Fab")
			(hide yes)
			(effects
				(font
					(size 1 1)
					(thickness 0.15)
				)
				(justify mirror)
			)
		)
		(property "Manufacturer" "Murata"
			(at 243.826501 43.265499 0)
			(layer "B.Fab")
			(hide yes)
			(effects
				(font
					(size 1 1)
					(thickness 0.15)
				)
				(justify mirror)
			)
		)
		(property "Val" "100n"
			(at 243.826501 43.265499 0)
			(layer "B.Fab")
			(hide yes)
			(effects
				(font
					(size 1 1)
					(thickness 0.15)
				)
				(justify mirror)
			)
		)
		(property "Voltage" "50V"
			(at 243.826501 43.265499 0)
			(layer "B.Fab")
			(hide yes)
			(effects
				(font
					(size 1 1)
					(thickness 0.15)
				)
				(justify mirror)
			)
		)
		(sheetname "/I^{2}C/")
		(sheetfile "i2c.kicad_sch")
		(attr smd)
		(fp_rect
			(start -0.9659 0.481258)
			(end 0.9649 -0.458742)
			(stroke
				(width 0.05)
				(type solid)
			)
			(fill no)
			(layer "B.CrtYd")
		)
		(fp_line
			(start 0.499 -0.248)
			(end -0.499 -0.248)
			(stroke
				(width 0.15)
				(type solid)
			)
			(layer "B.Fab")
		)
		(fp_line
			(start -0.499 -0.248)
			(end -0.499 0.25)
			(stroke
				(width 0.15)
				(type solid)
			)
			(layer "B.Fab")
		)
		(fp_line
			(start 0.499 0.25)
			(end 0.499 -0.248)
			(stroke
				(width 0.15)
				(type solid)
			)
			(layer "B.Fab")
		)
		(fp_line
			(start -0.499 0.25)
			(end 0.499 0.25)
			(stroke
				(width 0.15)
				(type solid)
			)
			(layer "B.Fab")
		)
		(pad "1" smd roundrect
			(at -0.484 0 90)
			(size 0.59 0.64)
			(layers "B.Cu" "B.Mask" "B.Paste")
			(roundrect_rratio 0.25)
			(net 200 "+3V3")
			(pintype "passive")
		)
		(pad "2" smd roundrect
			(at 0.484 0 90)
			(size 0.59 0.64)
			(layers "B.Cu" "B.Mask" "B.Paste")
			(roundrect_rratio 0.25)
			(net 1 "GND")
			(pintype "passive")
		)
	)
	(footprint "antmicro-footprints:C_0402_1005Metric"
		(layer "B.Cu")
		(at 115.580501 176.926 -90)
		(descr "Capacitor SMD 0402")
		(tags "capacitor SMD 0402")
		(property "Reference" "C2"
			(at 0 0.699 90)
			(layer "B.SilkS")
			(hide yes)
			(effects
				(font
					(size 0.7 0.7)
					(thickness 0.15)
				)
				(justify left bottom mirror)
			)
		)
		(property "Value" "C_100n_0402"
			(at -1.022927 -2.155213 90)
			(layer "B.Fab")
			(effects
				(font
					(size 0.7 0.7)
					(thickness 0.15)
				)
				(justify left bottom mirror)
			)
		)
		(property "Datasheet" "https://www.murata.com/products/productdetail?partno=GRM155R61H104KE14%23"
			(at 0 0 270)
			(layer "F.Fab")
			(hide yes)
			(effects
				(font
					(size 1.27 1.27)
					(thickness 0.15)
				)
			)
		)
		(property "Author" "Antmicro"
			(at -61.345499 292.506501 0)
			(layer "B.Fab")
			(hide yes)
			(effects
				(font
					(size 1 1)
					(thickness 0.15)
				)
				(justify mirror)
			)
		)
		(property "Dielectric" "X5R"
			(at -61.345499 292.506501 0)
			(layer "B.Fab")
			(hide yes)
			(effects
				(font
					(size 1 1)
					(thickness 0.15)
				)
				(justify mirror)
			)
		)
		(property "License" "Apache-2.0"
			(at -61.345499 292.506501 0)
			(layer "B.Fab")
			(hide yes)
			(effects
				(font
					(size 1 1)
					(thickness 0.15)
				)
				(justify mirror)
			)
		)
		(property "MPN" "GRM155R61H104KE14D"
			(at -61.345499 292.506501 0)
			(layer "B.Fab")
			(hide yes)
			(effects
				(font
					(size 1 1)
					(thickness 0.15)
				)
				(justify mirror)
			)
		)
		(property "Manufacturer" "Murata"
			(at -61.345499 292.506501 0)
			(layer "B.Fab")
			(hide yes)
			(effects
				(font
					(size 1 1)
					(thickness 0.15)
				)
				(justify mirror)
			)
		)
		(property "Val" "100n"
			(at -61.345499 292.506501 0)
			(layer "B.Fab")
			(hide yes)
			(effects
				(font
					(size 1 1)
					(thickness 0.15)
				)
				(justify mirror)
			)
		)
		(property "Voltage" "50V"
			(at -61.345499 292.506501 0)
			(layer "B.Fab")
			(hide yes)
			(effects
				(font
					(size 1 1)
					(thickness 0.15)
				)
				(justify mirror)
			)
		)
		(sheetname "/HyperRAM + QSPI Flash/")
		(sheetfile "hyperram-flash.kicad_sch")
		(attr smd)
		(fp_rect
			(start -0.9659 0.481258)
			(end 0.9649 -0.458742)
			(stroke
				(width 0.05)
				(type solid)
			)
			(fill no)
			(layer "B.CrtYd")
		)
		(fp_line
			(start -0.499 0.25)
			(end 0.499 0.25)
			(stroke
				(width 0.15)
				(type solid)
			)
			(layer "B.Fab")
		)
		(fp_line
			(start 0.499 0.25)
			(end 0.499 -0.248)
			(stroke
				(width 0.15)
				(type solid)
			)
			(layer "B.Fab")
		)
		(fp_line
			(start -0.499 -0.248)
			(end -0.499 0.25)
			(stroke
				(width 0.15)
				(type solid)
			)
			(layer "B.Fab")
		)
		(fp_line
			(start 0.499 -0.248)
			(end -0.499 -0.248)
			(stroke
				(width 0.15)
				(type solid)
			)
			(layer "B.Fab")
		)
		(pad "1" smd roundrect
			(at -0.484 0 270)
			(size 0.59 0.64)
			(layers "B.Cu" "B.Mask" "B.Paste")
			(roundrect_rratio 0.25)
			(net 200 "+3V3")
			(pintype "passive")
		)
		(pad "2" smd roundrect
			(at 0.484 0 270)
			(size 0.59 0.64)
			(layers "B.Cu" "B.Mask" "B.Paste")
			(roundrect_rratio 0.25)
			(net 1 "GND")
			(pintype "passive")
		)
	)
	(footprint "antmicro-footprints:C_0402_1005Metric"
		(layer "B.Cu")
		(at 149.875001 176.3)
		(descr "Capacitor SMD 0402 (1005 Metric), square (rectangular) end terminal, IPC_7351 nominal, (Body size source: IPC-SM-782 page 76, https://www.pcb-3d.com/wordpress/wp-content/uploads/ipc-sm-782a_amendment_1_and_2.pdf)")
		(tags "capacitor 0402")
		(property "Reference" "C104"
			(at 0 1.17 180)
			(layer "B.SilkS")
			(hide yes)
			(effects
				(font
					(size 0.7 0.7)
					(thickness 0.15)
				)
				(justify left bottom mirror)
			)
		)
		(property "Value" "C_100n_0402"
			(at 0 -1.169 180)
			(layer "B.Fab")
			(effects
				(font
					(size 0.7 0.7)
					(thickness 0.15)
				)
				(justify left bottom mirror)
			)
		)
		(property "Datasheet" "https://www.murata.com/products/productdetail?partno=GRM155R61H104KE14%23"
			(at 0 0 0)
			(layer "F.Fab")
			(hide yes)
			(effects
				(font
					(size 1.27 1.27)
					(thickness 0.15)
				)
			)
		)
		(property "Author" "Antmicro"
			(at 0 0 0)
			(layer "B.Fab")
			(hide yes)
			(effects
				(font
					(size 1 1)
					(thickness 0.15)
				)
				(justify mirror)
			)
		)
		(property "Dielectric" "X5R"
			(at 0 0 0)
			(layer "B.Fab")
			(hide yes)
			(effects
				(font
					(size 1 1)
					(thickness 0.15)
				)
				(justify mirror)
			)
		)
		(property "License" "Apache-2.0"
			(at 0 0 0)
			(layer "B.Fab")
			(hide yes)
			(effects
				(font
					(size 1 1)
					(thickness 0.15)
				)
				(justify mirror)
			)
		)
		(property "MPN" "GRM155R61H104KE14D"
			(at 0 0 0)
			(layer "B.Fab")
			(hide yes)
			(effects
				(font
					(size 1 1)
					(thickness 0.15)
				)
				(justify mirror)
			)
		)
		(property "Manufacturer" "Murata"
			(at 0 0 0)
			(layer "B.Fab")
			(hide yes)
			(effects
				(font
					(size 1 1)
					(thickness 0.15)
				)
				(justify mirror)
			)
		)
		(property "Val" "100n"
			(at 0 0 0)
			(layer "B.Fab")
			(hide yes)
			(effects
				(font
					(size 1 1)
					(thickness 0.15)
				)
				(justify mirror)
			)
		)
		(property "Voltage" "50V"
			(at 0 0 0)
			(layer "B.Fab")
			(hide yes)
			(effects
				(font
					(size 1 1)
					(thickness 0.15)
				)
				(justify mirror)
			)
		)
		(sheetname "/FPGA power/")
		(sheetfile "fpga-power.kicad_sch")
		(attr smd)
		(fp_rect
			(start -0.9656 0.4572)
			(end 0.9652 -0.4828)
			(stroke
				(width 0.05)
				(type solid)
			)
			(fill no)
			(layer "B.CrtYd")
		)
		(fp_line
			(start -0.5 -0.248)
			(end -0.5 0.25)
			(stroke
				(width 0.15)
				(type solid)
			)
			(layer "B.Fab")
		)
		(fp_line
			(start -0.5 0.25)
			(end 0.498 0.25)
			(stroke
				(width 0.15)
				(type solid)
			)
			(layer "B.Fab")
		)
		(fp_line
			(start 0.498 -0.248)
			(end -0.5 -0.248)
			(stroke
				(width 0.15)
				(type solid)
			)
			(layer "B.Fab")
		)
		(fp_line
			(start 0.498 0.25)
			(end 0.498 -0.248)
			(stroke
				(width 0.15)
				(type solid)
			)
			(layer "B.Fab")
		)
		(pad "1" smd roundrect
			(at -0.5 0 270)
			(size 0.6 0.6)
			(layers "B.Cu" "B.Mask" "B.Paste")
			(roundrect_rratio 0.25)
			(net 1 "GND")
			(pintype "passive")
		)
		(pad "2" smd roundrect
			(at 0.498 0)
			(size 0.6 0.6)
			(layers "B.Cu" "B.Mask" "B.Paste")
			(roundrect_rratio 0.25)
			(net 226 "+1V2_MGTAVTT")
			(pintype "passive")
		)
	)
)
